FILE_TYPE=LIBRARY_PARTS;
primitive 'FSA3357', 'FSA3357_SM';
  pin
    'A':
      PIN_NUMBER='(7)';
      BIDIRECTIONAL='TRUE';
      INPUT_LOAD='(-0.01,0.01)';
      OUTPUT_LOAD='(1.0,-1.0)';
    'B0':
      PIN_NUMBER='(1)';
      BIDIRECTIONAL='TRUE';
      INPUT_LOAD='(-0.01,0.01)';
      OUTPUT_LOAD='(1.0,-1.0)';
    'B1':
      PIN_NUMBER='(2)';
      BIDIRECTIONAL='TRUE';
      INPUT_LOAD='(-0.01,0.01)';
      OUTPUT_LOAD='(1.0,-1.0)';
    'B2':
      PIN_NUMBER='(3)';
      BIDIRECTIONAL='TRUE';
      INPUT_LOAD='(-0.01,0.01)';
      OUTPUT_LOAD='(1.0,-1.0)';
    'GND':
      PIN_NUMBER='(4)';
      PINUSE='GROUND';
      NO_LOAD_CHECK='Both';
      NO_IO_CHECK='Both';
      NO_ASSERT_CHECK='TRUE';
      NO_DIR_CHECK='TRUE';
      ALLOW_CONNECT='TRUE';
    'S1':
      PIN_NUMBER='(6)';
      INPUT_LOAD='(-0.01,0.01)';
    'S2':
      PIN_NUMBER='(5)';
      INPUT_LOAD='(-0.01,0.01)';
    'VCC':
      PIN_NUMBER='(8)';
      PINUSE='POWER';
      NO_LOAD_CHECK='Both';
      NO_IO_CHECK='Both';
      NO_ASSERT_CHECK='TRUE';
      NO_DIR_CHECK='TRUE';
      ALLOW_CONNECT='TRUE';
  end_pin;
  body
    PART_NAME='FSA3357';
    PHYS_DES_PREFIX='U';
  end_body;
end_primitive;

END.
